(kicad_pcb
	(version 20241229)
	(generator "pcbnew")
	(generator_version "9.0")
	(general
		(thickness 1.6)
		(legacy_teardrops no)
	)
	(paper "A4")
	(title_block
		(title "GMSL Deserializer")
		(date "2025-10-09")
		(rev "1.0.4")
		(company "Antmicro Ltd")
		(comment 1 "www.antmicro.com")
		(comment 9 "footprints 234-235 of 235")
	)
	(layers
		(0 "F.Cu" signal)
		(4 "In1.Cu" power)
		(6 "In2.Cu" power)
		(2 "B.Cu" signal)
		(9 "F.Adhes" user "F.Adhesive")
		(11 "B.Adhes" user "B.Adhesive")
		(13 "F.Paste" user)
		(15 "B.Paste" user)
		(5 "F.SilkS" user "F.Silkscreen")
		(7 "B.SilkS" user "B.Silkscreen")
		(1 "F.Mask" user)
		(3 "B.Mask" user)
		(17 "Dwgs.User" user "User.Drawings")
		(19 "Cmts.User" user "User.Comments")
		(21 "Eco1.User" user "User.Eco1")
		(23 "Eco2.User" user "User.Eco2")
		(25 "Edge.Cuts" user)
		(27 "Margin" user)
		(31 "F.CrtYd" user "F.Courtyard")
		(29 "B.CrtYd" user "B.Courtyard")
		(35 "F.Fab" user)
		(33 "B.Fab" user)
	)
	(footprint "antmicro-footprints:R_0402_1005Metric"
		(layer "B.Cu")
		(at 152.43253 96.385897 90)
		(descr "Resistor SMD 0402")
		(tags "resistor SMD 0402")
		(property "Reference" "R7"
			(at 5.775194 0.427452 90)
			(layer "B.SilkS")
			(effects
				(font
					(size 0.7 0.7)
					(thickness 0.15)
				)
				(justify right bottom mirror)
			)
		)
		(property "Value" "R_470R_0402"
			(at -1.011843 -1.772046 90)
			(layer "B.Fab")
			(effects
				(font
					(size 0.7 0.7)
					(thickness 0.15)
				)
				(justify right bottom mirror)
			)
		)
		(property "Datasheet" "https://www.bourns.com/docs/product-datasheets/cr.pdf"
			(at 0 0 90)
			(layer "F.Fab")
			(hide yes)
			(effects
				(font
					(size 1.27 1.27)
					(thickness 0.15)
				)
			)
		)
		(property "Description" "SMD Chip Resistor, 470 ohm, ± 1%, 62.5 mW, 0402 [1005 Metric], Thick Film, General Purpose"
			(at 0 0 90)
			(layer "F.Fab")
			(hide yes)
			(effects
				(font
					(size 1.27 1.27)
					(thickness 0.15)
				)
			)
		)
		(property "Author" "Antmicro"
			(at 328.456079 55.454932 135)
			(layer "B.Fab")
			(hide yes)
			(effects
				(font
					(size 1 1)
					(thickness 0.15)
				)
				(justify mirror)
			)
		)
		(property "License" "Apache-2.0"
			(at 328.456079 55.454932 135)
			(layer "B.Fab")
			(hide yes)
			(effects
				(font
					(size 1 1)
					(thickness 0.15)
				)
				(justify mirror)
			)
		)
		(property "MPN" "CR0402-FX-4700GLF"
			(at 328.456079 55.454932 135)
			(layer "B.Fab")
			(hide yes)
			(effects
				(font
					(size 1 1)
					(thickness 0.15)
				)
				(justify mirror)
			)
		)
		(property "Manufacturer" "Bourns"
			(at 328.456079 55.454932 135)
			(layer "B.Fab")
			(hide yes)
			(effects
				(font
					(size 1 1)
					(thickness 0.15)
				)
				(justify mirror)
			)
		)
		(property "Tolerance" "1%"
			(at 328.456079 55.454932 135)
			(layer "B.Fab")
			(hide yes)
			(effects
				(font
					(size 1 1)
					(thickness 0.15)
				)
				(justify mirror)
			)
		)
		(property "Val" "470R"
			(at 328.456079 55.454932 135)
			(layer "B.Fab")
			(hide yes)
			(effects
				(font
					(size 1 1)
					(thickness 0.15)
				)
				(justify mirror)
			)
		)
		(sheetname "/Connectors/")
		(sheetfile "connectors.kicad_sch")
		(attr smd)
		(fp_poly
			(pts
				(xy -0.925 0.47) (xy 0.925 0.47) (xy 0.925 -0.47) (xy -0.925 -0.47)
			)
			(stroke
				(width 0.05)
				(type default)
			)
			(fill no)
			(layer "B.CrtYd")
		)
		(fp_poly
			(pts
				(xy -0.5 0.25) (xy 0.5 0.25) (xy 0.5 -0.25) (xy -0.5 -0.25)
			)
			(stroke
				(width 0.15)
				(type solid)
			)
			(fill no)
			(layer "B.Fab")
		)
		(pad "1" smd roundrect
			(at -0.48 0 90)
			(size 0.59 0.64)
			(layers "B.Cu" "B.Mask" "B.Paste")
			(roundrect_rratio 0.25)
			(net 1 "GND")
			(pintype "passive")
		)
		(pad "2" smd roundrect
			(at 0.48 0 90)
			(size 0.59 0.64)
			(layers "B.Cu" "B.Mask" "B.Paste")
			(roundrect_rratio 0.25)
			(net 64 "Net-(D2-C)")
			(pintype "passive")
		)
	)
	(footprint "antmicro-footprints:Spacer_Drill3.7mm_H6mm_9774060151R"
		(layer "B.Cu")
		(at 123.372 93.068 180)
		(descr "Spacer M=3 h=36mm fi=5.1mm")
		(property "Reference" "H4"
			(at 0 3.2 0)
			(layer "B.SilkS")
			(effects
				(font
					(size 0.7 0.7)
					(thickness 0.15)
				)
				(justify left bottom mirror)
			)
		)
		(property "Value" "Spacer_Drill3.7mm_H6mm_9774060151R"
			(at 0 -4 0)
			(layer "B.Fab")
			(effects
				(font
					(size 0.7 0.7)
					(thickness 0.15)
				)
				(justify left bottom mirror)
			)
		)
		(property "Datasheet" "https://www.we-online.com/components/products/datasheet/9774060151R.pdf"
			(at 0 0 180)
			(layer "F.Fab")
			(hide yes)
			(effects
				(font
					(size 1.27 1.27)
					(thickness 0.15)
				)
			)
		)
		(property "Description" "Spacer, SMT, Non Stop, Steel, Swage Round, 5.1 mm x 6 mm, M2.5 Thread, WA-SMSI Series"
			(at 0 0 180)
			(layer "F.Fab")
			(hide yes)
			(effects
				(font
					(size 1.27 1.27)
					(thickness 0.15)
				)
			)
		)
		(property "Author" "Antmicro"
			(at 246.744 186.136 0)
			(layer "B.Fab")
			(hide yes)
			(effects
				(font
					(size 1 1)
					(thickness 0.15)
				)
				(justify mirror)
			)
		)
		(property "License" "Apache-2.0"
			(at 246.744 186.136 0)
			(layer "B.Fab")
			(hide yes)
			(effects
				(font
					(size 1 1)
					(thickness 0.15)
				)
				(justify mirror)
			)
		)
		(property "MPN" "9774060151R"
			(at 246.744 186.136 0)
			(layer "B.Fab")
			(hide yes)
			(effects
				(font
					(size 1 1)
					(thickness 0.15)
				)
				(justify mirror)
			)
		)
		(property "Manufacturer" "Würth Elektronik"
			(at 246.744 186.136 0)
			(layer "B.Fab")
			(hide yes)
			(effects
				(font
					(size 1 1)
					(thickness 0.15)
				)
				(justify mirror)
			)
		)
		(sheetname "/")
		(sheetfile "gmsl-deserializer.kicad_sch")
		(solder_paste_margin_ratio -1)
		(attr smd)
		(fp_circle
			(center 0 0)
			(end 3.05 0)
			(stroke
				(width 0.05)
				(type solid)
			)
			(fill no)
			(layer "B.CrtYd")
		)
		(fp_circle
			(center 0 0)
			(end 2.6 0)
			(stroke
				(width 0.15)
				(type solid)
			)
			(fill no)
			(layer "B.Fab")
		)
		(pad "" smd custom
			(at -1.7 -1.7 90)
			(size 0.62 0.62)
			(layers "B.Paste")
			(thermal_bridge_angle 90)
			(options
				(clearance outline)
				(anchor circle)
			)
			(primitives
				(gr_arc
					(start 1.266786 0.24747)
					(mid 0.285453 -0.29439)
					(end -0.250195 -1.279127)
					(width 0.2)
				)
				(gr_arc
					(start 1.259603 0.339191)
					(mid 0.218448 -0.232561)
					(end -0.34334 -1.279127)
					(width 0.2)
				)
				(gr_arc
					(start 1.255279 0.431435)
					(mid 0.152481 -0.169693)
					(end -0.436309 -1.279127)
					(width 0.2)
				)
				(gr_arc
					(start 1.253811 0.524161)
					(mid 0.087542 -0.105784)
					(end -0.529126 -1.279127)
					(width 0.2)
				)
				(gr_arc
					(start 1.275473 0.621136)
					(mid 0.0309 -0.033527)
					(end -0.621807 -1.279127)
					(width 0.2)
				)
				(gr_arc
					(start 1.263664 0.711602)
					(mid -0.037759 0.026651)
					(end -0.71437 -1.279127)
					(width 0.2)
				)
				(gr_arc
					(start 1.253435 0.802342)
					(mid -0.105837 0.087395)
					(end -0.806826 -1.279127)
					(width 0.2)
				)
				(gr_arc
					(start 1.267475 0.897258)
					(mid -0.165236 0.156885)
					(end -0.899187 -1.279127)
					(width 0.2)
				)
				(gr_arc
					(start 1.270645 0.990112)
					(mid -0.228522 0.222449)
					(end -0.991463 -1.279127)
					(width 0.2)
				)
				(gr_arc
					(start 1.266278 1.081674)
					(mid -0.294507 0.285313)
					(end -1.083663 -1.279127)
					(width 0.2)
				)
				(gr_line
					(start 1.279127 0.250195)
					(end 1.279127 1.083663)
					(width 0.2)
				)
				(gr_line
					(start -0.250195 -1.279127)
					(end -1.083663 -1.279127)
					(width 0.2)
				)
			)
		)
		(pad "" smd custom
			(at -1.7 1.7 180)
			(size 0.62 0.62)
			(layers "B.Paste")
			(thermal_bridge_angle 90)
			(options
				(clearance outline)
				(anchor circle)
			)
			(primitives
				(gr_arc
					(start 1.266786 0.24747)
					(mid 0.285453 -0.29439)
					(end -0.250195 -1.279127)
					(width 0.2)
				)
				(gr_arc
					(start 1.259603 0.339191)
					(mid 0.218448 -0.232561)
					(end -0.34334 -1.279127)
					(width 0.2)
				)
				(gr_arc
					(start 1.255279 0.431435)
					(mid 0.152481 -0.169693)
					(end -0.436309 -1.279127)
					(width 0.2)
				)
				(gr_arc
					(start 1.253811 0.524161)
					(mid 0.087542 -0.105784)
					(end -0.529126 -1.279127)
					(width 0.2)
				)
				(gr_arc
					(start 1.275473 0.621136)
					(mid 0.0309 -0.033527)
					(end -0.621807 -1.279127)
					(width 0.2)
				)
				(gr_arc
					(start 1.263664 0.711602)
					(mid -0.037759 0.026651)
					(end -0.71437 -1.279127)
					(width 0.2)
				)
				(gr_arc
					(start 1.253435 0.802342)
					(mid -0.105837 0.087395)
					(end -0.806826 -1.279127)
					(width 0.2)
				)
				(gr_arc
					(start 1.267475 0.897258)
					(mid -0.165236 0.156885)
					(end -0.899187 -1.279127)
					(width 0.2)
				)
				(gr_arc
					(start 1.270645 0.990112)
					(mid -0.228522 0.222449)
					(end -0.991463 -1.279127)
					(width 0.2)
				)
				(gr_arc
					(start 1.266278 1.081674)
					(mid -0.294507 0.285313)
					(end -1.083663 -1.279127)
					(width 0.2)
				)
				(gr_line
					(start 1.279127 0.250195)
					(end 1.279127 1.083663)
					(width 0.2)
				)
				(gr_line
					(start -0.250195 -1.279127)
					(end -1.083663 -1.279127)
					(width 0.2)
				)
			)
		)
		(pad "" smd custom
			(at 1.7 -1.7)
			(size 0.62 0.62)
			(layers "B.Paste")
			(thermal_bridge_angle 90)
			(options
				(clearance outline)
				(anchor circle)
			)
			(primitives
				(gr_arc
					(start 1.266786 0.24747)
					(mid 0.285453 -0.29439)
					(end -0.250195 -1.279127)
					(width 0.2)
				)
				(gr_arc
					(start 1.259603 0.339191)
					(mid 0.218448 -0.232561)
					(end -0.34334 -1.279127)
					(width 0.2)
				)
				(gr_arc
					(start 1.255279 0.431435)
					(mid 0.152481 -0.169693)
					(end -0.436309 -1.279127)
					(width 0.2)
				)
				(gr_arc
					(start 1.253811 0.524161)
					(mid 0.087542 -0.105784)
					(end -0.529126 -1.279127)
					(width 0.2)
				)
				(gr_arc
					(start 1.275473 0.621136)
					(mid 0.0309 -0.033527)
					(end -0.621807 -1.279127)
					(width 0.2)
				)
				(gr_arc
					(start 1.263664 0.711602)
					(mid -0.037759 0.026651)
					(end -0.71437 -1.279127)
					(width 0.2)
				)
				(gr_arc
					(start 1.253435 0.802342)
					(mid -0.105837 0.087395)
					(end -0.806826 -1.279127)
					(width 0.2)
				)
				(gr_arc
					(start 1.267475 0.897258)
					(mid -0.165236 0.156885)
					(end -0.899187 -1.279127)
					(width 0.2)
				)
				(gr_arc
					(start 1.270645 0.990112)
					(mid -0.228522 0.222449)
					(end -0.991463 -1.279127)
					(width 0.2)
				)
				(gr_arc
					(start 1.266278 1.081674)
					(mid -0.294507 0.285313)
					(end -1.083663 -1.279127)
					(width 0.2)
				)
				(gr_line
					(start 1.279127 0.250195)
					(end 1.279127 1.083663)
					(width 0.2)
				)
				(gr_line
					(start -0.250195 -1.279127)
					(end -1.083663 -1.279127)
					(width 0.2)
				)
			)
		)
		(pad "" smd custom
			(at 1.7 1.7 270)
			(size 0.62 0.62)
			(layers "B.Paste")
			(thermal_bridge_angle 90)
			(options
				(clearance outline)
				(anchor circle)
			)
			(primitives
				(gr_arc
					(start 1.266786 0.24747)
					(mid 0.285453 -0.29439)
					(end -0.250195 -1.279127)
					(width 0.2)
				)
				(gr_arc
					(start 1.259603 0.339191)
					(mid 0.218448 -0.232561)
					(end -0.34334 -1.279127)
					(width 0.2)
				)
				(gr_arc
					(start 1.255279 0.431435)
					(mid 0.152481 -0.169693)
					(end -0.436309 -1.279127)
					(width 0.2)
				)
				(gr_arc
					(start 1.253811 0.524161)
					(mid 0.087542 -0.105784)
					(end -0.529126 -1.279127)
					(width 0.2)
				)
				(gr_arc
					(start 1.275473 0.621136)
					(mid 0.0309 -0.033527)
					(end -0.621807 -1.279127)
					(width 0.2)
				)
				(gr_arc
					(start 1.263664 0.711602)
					(mid -0.037759 0.026651)
					(end -0.71437 -1.279127)
					(width 0.2)
				)
				(gr_arc
					(start 1.253435 0.802342)
					(mid -0.105837 0.087395)
					(end -0.806826 -1.279127)
					(width 0.2)
				)
				(gr_arc
					(start 1.267475 0.897258)
					(mid -0.165236 0.156885)
					(end -0.899187 -1.279127)
					(width 0.2)
				)
				(gr_arc
					(start 1.270645 0.990112)
					(mid -0.228522 0.222449)
					(end -0.991463 -1.279127)
					(width 0.2)
				)
				(gr_arc
					(start 1.266278 1.081674)
					(mid -0.294507 0.285313)
					(end -1.083663 -1.279127)
					(width 0.2)
				)
				(gr_line
					(start 1.279127 0.250195)
					(end 1.279127 1.083663)
					(width 0.2)
				)
				(gr_line
					(start -0.250195 -1.279127)
					(end -1.083663 -1.279127)
					(width 0.2)
				)
			)
		)
		(pad "1" thru_hole circle
			(at 0 0 180)
			(size 6 6)
			(drill 3.7)
			(layers "*.Cu" "*.Mask")
			(remove_unused_layers no)
			(net 1 "GND")
			(pintype "passive")
		)
	)
)
